(kicad_pcb
	(version 20260206)
	(generator "pcbnew")
	(generator_version "10.0")
	(general
		(thickness 1.6)
		(legacy_teardrops no)
	)
	(paper "A4")
	(title_block
		(title "04192023_DAF0TMB3IC0_F0TG_MB_C_brd_V02_OCP.brd")
		(comment 1 "Grand Teton / footprints 3923-3929 of 8354")
	)
	(layers
		(0 "F.Cu" signal "TOP")
		(4 "In1.Cu" signal "GND")
		(6 "In2.Cu" signal "IN1")
		(8 "In3.Cu" signal "GND1")
		(10 "In4.Cu" signal "IN2")
		(12 "In5.Cu" signal "GND2")
		(14 "In6.Cu" signal "IN3")
		(16 "In7.Cu" signal "GND3")
		(18 "In8.Cu" signal "VCC")
		(20 "In9.Cu" signal "VCC1")
		(22 "In10.Cu" signal "GND4")
		(24 "In11.Cu" signal "IN4")
		(26 "In12.Cu" signal "GND5")
		(28 "In13.Cu" signal "IN5")
		(30 "In14.Cu" signal "GND6")
		(32 "In15.Cu" signal "IN6")
		(34 "In16.Cu" signal "GND7")
		(2 "B.Cu" signal "BOTTOM")
		(9 "F.Adhes" user "F.Adhesive")
		(11 "B.Adhes" user "B.Adhesive")
		(13 "F.Paste" user "Package Geometry/Pastemask Top")
		(15 "B.Paste" user "Package Geometry/Pastemask Bottom")
		(5 "F.SilkS" user "Ref Des/Silkscreen Top")
		(7 "B.SilkS" user "Ref Des/Silkscreen Bottom")
		(1 "F.Mask" user "Board Geometry/Soldermask Top")
		(3 "B.Mask" user "Board Geometry/Soldermask Bottom")
		(17 "Dwgs.User" user "User.Drawings")
		(19 "Cmts.User" user "User.Comments")
		(21 "Eco1.User" user "User.Eco1")
		(23 "Eco2.User" user "User.Eco2")
		(25 "Edge.Cuts" user "Board Geometry/Outline")
		(27 "Margin" user)
		(31 "F.CrtYd" user "Package Geometry/Place Bound Top")
		(29 "B.CrtYd" user "Package Geometry/Place Bound Bottom")
		(35 "F.Fab" user "Ref Des/Assembly Top")
		(33 "B.Fab" user "Ref Des/Assembly Bottom")
	)
	(footprint ""
		(layer "F.Cu")
		(at 305.009296 -383.88163 -90)
		(property "Reference" "C924"
			(at 0 0 270)
			(layer "F.SilkS")
			(hide yes)
			(effects
				(font
					(size 1.27 1.27)
				)
			)
		)
		(property "Value" ""
			(at 0 0 270)
			(layer "F.Fab")
			(effects
				(font
					(size 1.27 1.27)
				)
			)
		)
		(duplicate_pad_numbers_are_jumpers no)
		(fp_line
			(start -0.299974 0.150114)
			(end -0.299974 -0.150114)
			(stroke
				(width 0.1)
				(type default)
			)
			(layer "F.Fab")
		)
		(fp_line
			(start 0.299974 0.150114)
			(end -0.299974 0.150114)
			(stroke
				(width 0.1)
				(type default)
			)
			(layer "F.Fab")
		)
		(fp_line
			(start -0.299974 -0.150114)
			(end 0.299974 -0.150114)
			(stroke
				(width 0.1)
				(type default)
			)
			(layer "F.Fab")
		)
		(fp_line
			(start 0.299974 -0.150114)
			(end 0.299974 0.150114)
			(stroke
				(width 0.1)
				(type default)
			)
			(layer "F.Fab")
		)
		(pad "1" smd rect
			(at -0.2667 0 270)
			(size 0.3048 0.381)
			(layers "F.Cu" "F.Mask" "F.Paste")
			(net "P5E_CPU0_P0_TX_C_DN<4>")
		)
		(pad "2" smd rect
			(at 0.2667 0 270)
			(size 0.3048 0.381)
			(layers "F.Cu" "F.Mask" "F.Paste")
			(net "P5E_CPU0_P0_TX_DN<4>")
		)
	)
	(footprint ""
		(layer "F.Cu")
		(at 506.185424 -306.9209 -90)
		(property "Reference" "X9002"
			(at -1.89738 4.962398 0)
			(unlocked yes)
			(layer "F.SilkS")
			(effects
				(font
					(size 0.7874 0.5842)
					(thickness 0.1524)
				)
				(justify left)
			)
		)
		(property "Value" ""
			(at 0 0 270)
			(layer "F.Fab")
			(effects
				(font
					(size 1.27 1.27)
				)
			)
		)
		(property "User Part Number" "N_A"
			(at 1.30175 1.27 0)
			(unlocked yes)
			(layer "Cmts.User")
			(hide yes)
			(effects
				(font
					(size 0.635 0.4064)
					(thickness 0.1524)
				)
			)
		)
		(property "Device Type" "TP_TDR_4P_FTS_TH-TP_TDR_4P_DIP,EMPTY,TP15"
			(at 1.30175 1.27 0)
			(unlocked yes)
			(layer "F.Fab")
			(hide yes)
			(effects
				(font
					(size 0.635 0.4064)
					(thickness 0.1524)
				)
			)
		)
		(duplicate_pad_numbers_are_jumpers no)
		(fp_line
			(start 0 3.81)
			(end 2.54 3.81)
			(stroke
				(width 0.1524)
				(type default)
			)
			(layer "F.SilkS")
		)
		(fp_line
			(start 2.54 3.81)
			(end 2.54 3.6703)
			(stroke
				(width 0.1524)
				(type default)
			)
			(layer "F.SilkS")
		)
		(fp_line
			(start 0 3.175)
			(end 0 3.81)
			(stroke
				(width 0.1524)
				(type default)
			)
			(layer "F.SilkS")
		)
		(fp_line
			(start 2.54 1.4097)
			(end 2.54 1.1303)
			(stroke
				(width 0.1524)
				(type default)
			)
			(layer "F.SilkS")
		)
		(fp_line
			(start 0 0.635)
			(end 0 1.905)
			(stroke
				(width 0.1524)
				(type default)
			)
			(layer "F.SilkS")
		)
		(fp_line
			(start 2.54 -1.1303)
			(end 2.54 -1.27)
			(stroke
				(width 0.1524)
				(type default)
			)
			(layer "F.SilkS")
		)
		(fp_line
			(start 0 -1.27)
			(end 0 -0.635)
			(stroke
				(width 0.1524)
				(type default)
			)
			(layer "F.SilkS")
		)
		(fp_line
			(start 2.54 -1.27)
			(end 0 -1.27)
			(stroke
				(width 0.1524)
				(type default)
			)
			(layer "F.SilkS")
		)
		(fp_poly
			(pts
				(xy -2.285746 -0.762) (xy -0.761746 0) (xy -2.285746 0.762)
			)
			(stroke
				(width 0)
				(type default)
			)
			(fill yes)
			(layer "F.SilkS")
		)
		(fp_line
			(start 0 3.81)
			(end 2.54 3.81)
			(stroke
				(width 0.1)
				(type default)
			)
			(layer "F.Fab")
		)
		(fp_line
			(start 2.54 3.81)
			(end 2.54 -1.27)
			(stroke
				(width 0.1)
				(type default)
			)
			(layer "F.Fab")
		)
		(fp_line
			(start 0 -1.27)
			(end 0 3.81)
			(stroke
				(width 0.1)
				(type default)
			)
			(layer "F.Fab")
		)
		(fp_line
			(start 2.54 -1.27)
			(end 0 -1.27)
			(stroke
				(width 0.1)
				(type default)
			)
			(layer "F.Fab")
		)
		(fp_poly
			(pts
				(xy -0.761746 0) (xy -2.285746 -0.762) (xy -2.285746 0.762)
			)
			(stroke
				(width 0)
				(type default)
			)
			(fill yes)
			(layer "F.Fab")
		)
		(pad "1" thru_hole circle
			(at 0 0 270)
			(size 1.0033 1.0033)
			(drill 0.249936)
			(layers "*.Cu" "*.Mask")
			(remove_unused_layers no)
			(net "TDR_DIFF_85_NECK_IN1_DP")
			(clearance 0.10795)
			(thermal_gap 0.10795)
			(padstack
				(mode front_inner_back)
				(layer "Inner"
					(shape circle)
					(size 0.8001 0.8001)
					(clearance 0.1524)
				)
				(layer "B.Cu"
					(shape circle)
					(size 1.0033 1.0033)
					(clearance 0.10795)
				)
			)
		)
		(pad "2" thru_hole circle
			(at 2.54 0 270)
			(size 1.9939 1.9939)
			(drill 0.249936)
			(layers "*.Cu" "*.Mask")
			(remove_unused_layers no)
			(net "T1_GND")
			(clearance 0.10795)
			(thermal_gap 0.10795)
			(padstack
				(mode front_inner_back)
				(layer "Inner"
					(shape circle)
					(size 0.8001 0.8001)
					(clearance 0.1524)
				)
				(layer "B.Cu"
					(shape circle)
					(size 1.9939 1.9939)
					(clearance 0.10795)
				)
			)
		)
		(pad "3" thru_hole circle
			(at 2.54 2.54 270)
			(size 1.9939 1.9939)
			(drill 0.249936)
			(layers "*.Cu" "*.Mask")
			(remove_unused_layers no)
			(net "T1_GND")
			(clearance 0.10795)
			(thermal_gap 0.10795)
			(padstack
				(mode front_inner_back)
				(layer "Inner"
					(shape circle)
					(size 0.8001 0.8001)
					(clearance 0.1524)
				)
				(layer "B.Cu"
					(shape circle)
					(size 1.9939 1.9939)
					(clearance 0.10795)
				)
			)
		)
		(pad "4" thru_hole circle
			(at 0 2.54 270)
			(size 1.0033 1.0033)
			(drill 0.249936)
			(layers "*.Cu" "*.Mask")
			(remove_unused_layers no)
			(net "TDR_DIFF_85_NECK_IN1_DN")
			(clearance 0.10795)
			(thermal_gap 0.10795)
			(padstack
				(mode front_inner_back)
				(layer "Inner"
					(shape circle)
					(size 0.8001 0.8001)
					(clearance 0.1524)
				)
				(layer "B.Cu"
					(shape circle)
					(size 1.0033 1.0033)
					(clearance 0.10795)
				)
			)
		)
	)
	(footprint ""
		(layer "F.Cu")
		(at 394.092684 -394.82268 90)
		(property "Reference" "C992"
			(at 0 0 90)
			(layer "F.SilkS")
			(hide yes)
			(effects
				(font
					(size 1.27 1.27)
				)
			)
		)
		(property "Value" ""
			(at 0 0 90)
			(layer "F.Fab")
			(effects
				(font
					(size 1.27 1.27)
				)
			)
		)
		(duplicate_pad_numbers_are_jumpers no)
		(fp_line
			(start 0.7874 -0.4064)
			(end 0.7874 0.4064)
			(stroke
				(width 0.1524)
				(type default)
			)
			(layer "F.SilkS")
		)
		(fp_line
			(start -0.7874 -0.4064)
			(end 0.7874 -0.4064)
			(stroke
				(width 0.1524)
				(type default)
			)
			(layer "F.SilkS")
		)
		(fp_line
			(start 0.7874 0.4064)
			(end -0.7874 0.4064)
			(stroke
				(width 0.1524)
				(type default)
			)
			(layer "F.SilkS")
		)
		(fp_line
			(start -0.7874 0.4064)
			(end -0.7874 -0.4064)
			(stroke
				(width 0.1524)
				(type default)
			)
			(layer "F.SilkS")
		)
		(fp_line
			(start -0.12065 -0.305054)
			(end -0.12065 -0.2794)
			(stroke
				(width 0.1)
				(type default)
			)
			(layer "F.Fab")
		)
		(fp_line
			(start -0.67945 -0.305054)
			(end -0.12065 -0.305054)
			(stroke
				(width 0.1)
				(type default)
			)
			(layer "F.Fab")
		)
		(fp_line
			(start 0.67945 -0.3048)
			(end 0.67945 0.3048)
			(stroke
				(width 0.1)
				(type default)
			)
			(layer "F.Fab")
		)
		(fp_line
			(start 0.12065 -0.3048)
			(end 0.67945 -0.3048)
			(stroke
				(width 0.1)
				(type default)
			)
			(layer "F.Fab")
		)
		(fp_line
			(start 0.12065 -0.2794)
			(end 0.12065 -0.3048)
			(stroke
				(width 0.1)
				(type default)
			)
			(layer "F.Fab")
		)
		(fp_line
			(start -0.12065 -0.2794)
			(end 0.12065 -0.2794)
			(stroke
				(width 0.1)
				(type default)
			)
			(layer "F.Fab")
		)
		(fp_line
			(start 0.120396 0.2794)
			(end -0.12065 0.2794)
			(stroke
				(width 0.1)
				(type default)
			)
			(layer "F.Fab")
		)
		(fp_line
			(start -0.12065 0.2794)
			(end -0.12065 0.3048)
			(stroke
				(width 0.1)
				(type default)
			)
			(layer "F.Fab")
		)
		(fp_line
			(start 0.67945 0.3048)
			(end 0.120396 0.3048)
			(stroke
				(width 0.1)
				(type default)
			)
			(layer "F.Fab")
		)
		(fp_line
			(start 0.120396 0.3048)
			(end 0.120396 0.2794)
			(stroke
				(width 0.1)
				(type default)
			)
			(layer "F.Fab")
		)
		(fp_line
			(start -0.12065 0.3048)
			(end -0.67945 0.3048)
			(stroke
				(width 0.1)
				(type default)
			)
			(layer "F.Fab")
		)
		(fp_line
			(start -0.67945 0.3048)
			(end -0.67945 -0.305054)
			(stroke
				(width 0.1)
				(type default)
			)
			(layer "F.Fab")
		)
		(pad "1" smd circle
			(at -0.40005 0 90)
			(size 0 0)
			(layers "F.Cu" "F.Mask" "F.Paste")
			(net "P1V8_CPU0_RT_1D")
		)
		(pad "2" smd circle
			(at 0.40005 0 90)
			(size 0 0)
			(layers "F.Cu" "F.Mask" "F.Paste")
			(net "GND")
		)
	)
	(footprint ""
		(layer "F.Cu")
		(at 366.415066 -424.002962 90)
		(property "Reference" "C2010"
			(at 0 0 90)
			(layer "F.SilkS")
			(hide yes)
			(effects
				(font
					(size 1.27 1.27)
				)
			)
		)
		(property "Value" ""
			(at 0 0 90)
			(layer "F.Fab")
			(effects
				(font
					(size 1.27 1.27)
				)
			)
		)
		(duplicate_pad_numbers_are_jumpers no)
		(fp_line
			(start 0.7874 -0.4064)
			(end 0.7874 0.4064)
			(stroke
				(width 0.1524)
				(type default)
			)
			(layer "F.SilkS")
		)
		(fp_line
			(start -0.7874 -0.4064)
			(end 0.7874 -0.4064)
			(stroke
				(width 0.1524)
				(type default)
			)
			(layer "F.SilkS")
		)
		(fp_line
			(start 0.7874 0.4064)
			(end -0.7874 0.4064)
			(stroke
				(width 0.1524)
				(type default)
			)
			(layer "F.SilkS")
		)
		(fp_line
			(start -0.7874 0.4064)
			(end -0.7874 -0.4064)
			(stroke
				(width 0.1524)
				(type default)
			)
			(layer "F.SilkS")
		)
		(fp_line
			(start -0.12065 -0.305054)
			(end -0.12065 -0.2794)
			(stroke
				(width 0.1)
				(type default)
			)
			(layer "F.Fab")
		)
		(fp_line
			(start -0.67945 -0.305054)
			(end -0.12065 -0.305054)
			(stroke
				(width 0.1)
				(type default)
			)
			(layer "F.Fab")
		)
		(fp_line
			(start 0.67945 -0.3048)
			(end 0.67945 0.3048)
			(stroke
				(width 0.1)
				(type default)
			)
			(layer "F.Fab")
		)
		(fp_line
			(start 0.12065 -0.3048)
			(end 0.67945 -0.3048)
			(stroke
				(width 0.1)
				(type default)
			)
			(layer "F.Fab")
		)
		(fp_line
			(start 0.12065 -0.2794)
			(end 0.12065 -0.3048)
			(stroke
				(width 0.1)
				(type default)
			)
			(layer "F.Fab")
		)
		(fp_line
			(start -0.12065 -0.2794)
			(end 0.12065 -0.2794)
			(stroke
				(width 0.1)
				(type default)
			)
			(layer "F.Fab")
		)
		(fp_line
			(start 0.120396 0.2794)
			(end -0.12065 0.2794)
			(stroke
				(width 0.1)
				(type default)
			)
			(layer "F.Fab")
		)
		(fp_line
			(start -0.12065 0.2794)
			(end -0.12065 0.3048)
			(stroke
				(width 0.1)
				(type default)
			)
			(layer "F.Fab")
		)
		(fp_line
			(start 0.67945 0.3048)
			(end 0.120396 0.3048)
			(stroke
				(width 0.1)
				(type default)
			)
			(layer "F.Fab")
		)
		(fp_line
			(start 0.120396 0.3048)
			(end 0.120396 0.2794)
			(stroke
				(width 0.1)
				(type default)
			)
			(layer "F.Fab")
		)
		(fp_line
			(start -0.12065 0.3048)
			(end -0.67945 0.3048)
			(stroke
				(width 0.1)
				(type default)
			)
			(layer "F.Fab")
		)
		(fp_line
			(start -0.67945 0.3048)
			(end -0.67945 -0.305054)
			(stroke
				(width 0.1)
				(type default)
			)
			(layer "F.Fab")
		)
		(pad "1" smd circle
			(at -0.40005 0 90)
			(size 0 0)
			(layers "F.Cu" "F.Mask" "F.Paste")
			(net "P3V3_AUX")
		)
		(pad "2" smd circle
			(at 0.40005 0 90)
			(size 0 0)
			(layers "F.Cu" "F.Mask" "F.Paste")
			(net "GND")
		)
	)
	(footprint ""
		(layer "F.Cu")
		(at 387.099302 -416.899344 -90)
		(property "Reference" "C6575"
			(at 0 0 270)
			(layer "F.SilkS")
			(hide yes)
			(effects
				(font
					(size 1.27 1.27)
				)
			)
		)
		(property "Value" ""
			(at 0 0 270)
			(layer "F.Fab")
			(effects
				(font
					(size 1.27 1.27)
				)
			)
		)
		(duplicate_pad_numbers_are_jumpers no)
		(fp_line
			(start -0.299974 0.150114)
			(end -0.299974 -0.150114)
			(stroke
				(width 0.1)
				(type default)
			)
			(layer "F.Fab")
		)
		(fp_line
			(start 0.299974 0.150114)
			(end -0.299974 0.150114)
			(stroke
				(width 0.1)
				(type default)
			)
			(layer "F.Fab")
		)
		(fp_line
			(start -0.299974 -0.150114)
			(end 0.299974 -0.150114)
			(stroke
				(width 0.1)
				(type default)
			)
			(layer "F.Fab")
		)
		(fp_line
			(start 0.299974 -0.150114)
			(end 0.299974 0.150114)
			(stroke
				(width 0.1)
				(type default)
			)
			(layer "F.Fab")
		)
		(pad "1" smd rect
			(at -0.2667 0 270)
			(size 0.3048 0.381)
			(layers "F.Cu" "F.Mask" "F.Paste")
			(net "P5E_CPU0_P2_TX_BUF_C_DP<5>")
		)
		(pad "2" smd rect
			(at 0.2667 0 270)
			(size 0.3048 0.381)
			(layers "F.Cu" "F.Mask" "F.Paste")
			(net "P5E_CPU0_P2_TX_BUF_DP<5>")
		)
	)
	(footprint ""
		(layer "F.Cu")
		(at 402.097748 -16.100298 90)
		(property "Reference" "C1557"
			(at 0 0 90)
			(layer "F.SilkS")
			(hide yes)
			(effects
				(font
					(size 1.27 1.27)
				)
			)
		)
		(property "Value" ""
			(at 0 0 90)
			(layer "F.Fab")
			(effects
				(font
					(size 1.27 1.27)
				)
			)
		)
		(duplicate_pad_numbers_are_jumpers no)
		(fp_line
			(start 0.299974 -0.150114)
			(end 0.299974 0.150114)
			(stroke
				(width 0.1)
				(type default)
			)
			(layer "F.Fab")
		)
		(fp_line
			(start -0.299974 -0.150114)
			(end 0.299974 -0.150114)
			(stroke
				(width 0.1)
				(type default)
			)
			(layer "F.Fab")
		)
		(fp_line
			(start 0.299974 0.150114)
			(end -0.299974 0.150114)
			(stroke
				(width 0.1)
				(type default)
			)
			(layer "F.Fab")
		)
		(fp_line
			(start -0.299974 0.150114)
			(end -0.299974 -0.150114)
			(stroke
				(width 0.1)
				(type default)
			)
			(layer "F.Fab")
		)
		(pad "1" smd rect
			(at -0.2667 0 90)
			(size 0.3048 0.381)
			(layers "F.Cu" "F.Mask" "F.Paste")
			(net "P5E_CPU0_G3_TX_C_DP<11>")
		)
		(pad "2" smd rect
			(at 0.2667 0 90)
			(size 0.3048 0.381)
			(layers "F.Cu" "F.Mask" "F.Paste")
			(net "P5E_CPU0_G3_TX_DP<11>")
		)
	)
	(footprint ""
		(layer "F.Cu")
		(at 111.252 -415.036 180)
		(property "Reference" "L1"
			(at 0 0 180)
			(layer "F.SilkS")
			(hide yes)
			(effects
				(font
					(size 1.27 1.27)
				)
			)
		)
		(property "Value" ""
			(at 0 0 180)
			(layer "F.Fab")
			(effects
				(font
					(size 1.27 1.27)
				)
			)
		)
		(duplicate_pad_numbers_are_jumpers no)
		(fp_line
			(start 1.63576 0.8128)
			(end -1.63576 0.8128)
			(stroke
				(width 0.1524)
				(type default)
			)
			(layer "F.SilkS")
		)
		(fp_line
			(start 1.63576 -0.8128)
			(end 1.63576 0.8128)
			(stroke
				(width 0.1524)
				(type default)
			)
			(layer "F.SilkS")
		)
		(fp_line
			(start -1.63576 -0.8128)
			(end 1.63576 -0.8128)
			(stroke
				(width 0.1524)
				(type default)
			)
			(layer "F.SilkS")
		)
		(fp_line
			(start -1.63576 -0.8128)
			(end -1.63576 0.8128)
			(stroke
				(width 0.1524)
				(type default)
			)
			(layer "F.SilkS")
		)
		(fp_line
			(start 1.560576 0.7366)
			(end 1.560576 -0.738632)
			(stroke
				(width 0.1)
				(type default)
			)
			(layer "F.Fab")
		)
		(fp_line
			(start 1.560576 -0.738632)
			(end -1.56083 -0.738632)
			(stroke
				(width 0.1)
				(type default)
			)
			(layer "F.Fab")
		)
		(fp_line
			(start 1.524 0.7366)
			(end 1.560576 0.7366)
			(stroke
				(width 0.1)
				(type default)
			)
			(layer "F.Fab")
		)
		(fp_line
			(start -1.524 0.7366)
			(end 1.524 0.7366)
			(stroke
				(width 0.1)
				(type default)
			)
			(layer "F.Fab")
		)
		(fp_line
			(start -1.56083 0.7366)
			(end -1.524 0.7366)
			(stroke
				(width 0.1)
				(type default)
			)
			(layer "F.Fab")
		)
		(fp_line
			(start -1.56083 -0.738632)
			(end -1.56083 0.7366)
			(stroke
				(width 0.1)
				(type default)
			)
			(layer "F.Fab")
		)
		(pad "1" smd rect
			(at -0.94996 0)
			(size 1.1176 1.3716)
			(layers "F.Cu" "F.Mask" "F.Paste")
			(net "P3V3_AUX")
		)
		(pad "2" smd rect
			(at 0.94996 0)
			(size 1.1176 1.3716)
			(layers "F.Cu" "F.Mask" "F.Paste")
			(net "P3V3_9ZXL045_P1")
		)
	)
)
